# S9S_MB_2U (Grand Teton) — schematic netlist excerpt (pin names and nets, part order shuffled) for the footprints in the layout excerpt that follows; sources: Cadence DE-HDL packaged netlist, KiCad conversion of 03242023_DA0F0TMBIJ0_F0T_Motherboard_J_brd_V01_OCP.brd

C886  Q_CAP_DIFFBUS  DIFF BUS_0.22UF 6.3V 20% X6S  pkg C0201  page 174 : \1\ = P5E_CPU0_PE3_TX_C_DN<7> ; \2\ = P5E_CPU0_PE3_TX_DN<7>
C307  Q_CAP  22UF 4V 20% X6S  pkg C0402  page 77 : A = PVCCIN_CPU1 ; B = GND
PR3914  Q_RES  2K 0.1% CHIP  pkg 0402LF  page 302 : A = HSC_CS_1 ; B = AGND_HSC

(kicad_pcb
	(version 20260206)
	(generator "pcbnew")
	(generator_version "10.0")
	(general
		(thickness 1.6)
		(legacy_teardrops no)
	)
	(paper "A4")
	(title_block
		(title "03242023_DA0F0TMBIJ0_F0T_Motherboard_J_brd_V01_OCP.brd")
		(comment 1 "Grand Teton / footprints 3316-3318 of 6105")
	)
	(layers
		(0 "F.Cu" signal "TOP")
		(4 "In1.Cu" signal "GND")
		(6 "In2.Cu" signal "IN1")
		(8 "In3.Cu" signal "GND1")
		(10 "In4.Cu" signal "IN2")
		(12 "In5.Cu" signal "GND2")
		(14 "In6.Cu" signal "IN3")
		(16 "In7.Cu" signal "GND3")
		(18 "In8.Cu" signal "VCC")
		(20 "In9.Cu" signal "VCC1")
		(22 "In10.Cu" signal "GND4")
		(24 "In11.Cu" signal "IN4")
		(26 "In12.Cu" signal "GND5")
		(28 "In13.Cu" signal "IN5")
		(30 "In14.Cu" signal "GND6")
		(32 "In15.Cu" signal "IN6")
		(34 "In16.Cu" signal "GND7")
		(2 "B.Cu" signal "BOTTOM")
		(9 "F.Adhes" user "F.Adhesive")
		(11 "B.Adhes" user "B.Adhesive")
		(13 "F.Paste" user "Package Geometry/Pastemask Top")
		(15 "B.Paste" user "Package Geometry/Pastemask Bottom")
		(5 "F.SilkS" user "Ref Des/Silkscreen Top")
		(7 "B.SilkS" user "Ref Des/Silkscreen Bottom")
		(1 "F.Mask" user "Board Geometry/Soldermask Top")
		(3 "B.Mask" user "Board Geometry/Soldermask Bottom")
		(17 "Dwgs.User" user "User.Drawings")
		(19 "Cmts.User" user "User.Comments")
		(21 "Eco1.User" user "User.Eco1")
		(23 "Eco2.User" user "User.Eco2")
		(25 "Edge.Cuts" user "Board Geometry/Outline")
		(27 "Margin" user)
		(31 "F.CrtYd" user "Package Geometry/Place Bound Top")
		(29 "B.CrtYd" user "Package Geometry/Place Bound Bottom")
		(35 "F.Fab" user "Ref Des/Assembly Top")
		(33 "B.Fab" user "Ref Des/Assembly Bottom")
	)
	(footprint ""
		(layer "F.Cu")
		(at 397.24965 -408.517344 -90)
		(property "Reference" "C886"
			(at 0 0 270)
			(layer "F.SilkS")
			(hide yes)
			(effects
				(font
					(size 1.27 1.27)
				)
			)
		)
		(property "Value" ""
			(at 0 0 270)
			(layer "F.Fab")
			(effects
				(font
					(size 1.27 1.27)
				)
			)
		)
		(duplicate_pad_numbers_are_jumpers no)
		(fp_line
			(start -0.299974 0.150114)
			(end -0.299974 -0.150114)
			(stroke
				(width 0.1)
				(type default)
			)
			(layer "F.Fab")
		)
		(fp_line
			(start 0.299974 0.150114)
			(end -0.299974 0.150114)
			(stroke
				(width 0.1)
				(type default)
			)
			(layer "F.Fab")
		)
		(fp_line
			(start -0.299974 -0.150114)
			(end 0.299974 -0.150114)
			(stroke
				(width 0.1)
				(type default)
			)
			(layer "F.Fab")
		)
		(fp_line
			(start 0.299974 -0.150114)
			(end 0.299974 0.150114)
			(stroke
				(width 0.1)
				(type default)
			)
			(layer "F.Fab")
		)
		(pad "1" smd rect
			(at -0.2667 0 270)
			(size 0.3048 0.381)
			(layers "F.Cu" "F.Mask" "F.Paste")
			(net "P5E_CPU0_PE3_TX_C_DN<7>")
		)
		(pad "2" smd rect
			(at 0.2667 0 270)
			(size 0.3048 0.381)
			(layers "F.Cu" "F.Mask" "F.Paste")
			(net "P5E_CPU0_PE3_TX_DN<7>")
		)
	)
	(footprint ""
		(layer "F.Cu")
		(at 107.2896 -249.320558 -90)
		(property "Reference" "C307"
			(at 0 0 270)
			(layer "F.SilkS")
			(hide yes)
			(effects
				(font
					(size 1.27 1.27)
				)
			)
		)
		(property "Value" ""
			(at 0 0 270)
			(layer "F.Fab")
			(effects
				(font
					(size 1.27 1.27)
				)
			)
		)
		(duplicate_pad_numbers_are_jumpers no)
		(fp_line
			(start -0.7874 0.4064)
			(end -0.7874 -0.4064)
			(stroke
				(width 0.1524)
				(type default)
			)
			(layer "F.SilkS")
		)
		(fp_line
			(start 0.7874 0.4064)
			(end -0.7874 0.4064)
			(stroke
				(width 0.1524)
				(type default)
			)
			(layer "F.SilkS")
		)
		(fp_line
			(start -0.7874 -0.4064)
			(end 0.7874 -0.4064)
			(stroke
				(width 0.1524)
				(type default)
			)
			(layer "F.SilkS")
		)
		(fp_line
			(start 0.7874 -0.4064)
			(end 0.7874 0.4064)
			(stroke
				(width 0.1524)
				(type default)
			)
			(layer "F.SilkS")
		)
		(fp_line
			(start -0.67945 0.3048)
			(end -0.67945 -0.305054)
			(stroke
				(width 0.1)
				(type default)
			)
			(layer "F.Fab")
		)
		(fp_line
			(start -0.12065 0.3048)
			(end -0.67945 0.3048)
			(stroke
				(width 0.1)
				(type default)
			)
			(layer "F.Fab")
		)
		(fp_line
			(start 0.120396 0.3048)
			(end 0.120396 0.2794)
			(stroke
				(width 0.1)
				(type default)
			)
			(layer "F.Fab")
		)
		(fp_line
			(start 0.67945 0.3048)
			(end 0.120396 0.3048)
			(stroke
				(width 0.1)
				(type default)
			)
			(layer "F.Fab")
		)
		(fp_line
			(start -0.12065 0.2794)
			(end -0.12065 0.3048)
			(stroke
				(width 0.1)
				(type default)
			)
			(layer "F.Fab")
		)
		(fp_line
			(start 0.120396 0.2794)
			(end -0.12065 0.2794)
			(stroke
				(width 0.1)
				(type default)
			)
			(layer "F.Fab")
		)
		(fp_line
			(start -0.12065 -0.2794)
			(end 0.12065 -0.2794)
			(stroke
				(width 0.1)
				(type default)
			)
			(layer "F.Fab")
		)
		(fp_line
			(start 0.12065 -0.2794)
			(end 0.12065 -0.3048)
			(stroke
				(width 0.1)
				(type default)
			)
			(layer "F.Fab")
		)
		(fp_line
			(start 0.12065 -0.3048)
			(end 0.67945 -0.3048)
			(stroke
				(width 0.1)
				(type default)
			)
			(layer "F.Fab")
		)
		(fp_line
			(start 0.67945 -0.3048)
			(end 0.67945 0.3048)
			(stroke
				(width 0.1)
				(type default)
			)
			(layer "F.Fab")
		)
		(fp_line
			(start -0.67945 -0.305054)
			(end -0.12065 -0.305054)
			(stroke
				(width 0.1)
				(type default)
			)
			(layer "F.Fab")
		)
		(fp_line
			(start -0.12065 -0.305054)
			(end -0.12065 -0.2794)
			(stroke
				(width 0.1)
				(type default)
			)
			(layer "F.Fab")
		)
		(pad "1" smd circle
			(at -0.40005 0 270)
			(size 0 0)
			(layers "F.Cu" "F.Mask" "F.Paste")
			(net "PVCCIN_CPU1")
		)
		(pad "2" smd circle
			(at 0.40005 0 270)
			(size 0 0)
			(layers "F.Cu" "F.Mask" "F.Paste")
			(net "GND")
		)
	)
	(footprint ""
		(layer "F.Cu")
		(at 194.856608 -400.784822 180)
		(property "Reference" "PR3914"
			(at 0 0 180)
			(layer "F.SilkS")
			(hide yes)
			(effects
				(font
					(size 1.27 1.27)
				)
			)
		)
		(property "Value" ""
			(at 0 0 180)
			(layer "F.Fab")
			(effects
				(font
					(size 1.27 1.27)
				)
			)
		)
		(duplicate_pad_numbers_are_jumpers no)
		(fp_line
			(start 0.7874 0.4064)
			(end -0.7874 0.4064)
			(stroke
				(width 0.1524)
				(type default)
			)
			(layer "F.SilkS")
		)
		(fp_line
			(start 0.7874 -0.4064)
			(end 0.7874 0.4064)
			(stroke
				(width 0.1524)
				(type default)
			)
			(layer "F.SilkS")
		)
		(fp_line
			(start -0.7874 0.4064)
			(end -0.7874 -0.4064)
			(stroke
				(width 0.1524)
				(type default)
			)
			(layer "F.SilkS")
		)
		(fp_line
			(start -0.7874 -0.4064)
			(end 0.7874 -0.4064)
			(stroke
				(width 0.1524)
				(type default)
			)
			(layer "F.SilkS")
		)
		(fp_line
			(start 0.67945 0.3048)
			(end 0.120396 0.3048)
			(stroke
				(width 0.1)
				(type default)
			)
			(layer "F.Fab")
		)
		(fp_line
			(start 0.67945 -0.3048)
			(end 0.67945 0.3048)
			(stroke
				(width 0.1)
				(type default)
			)
			(layer "F.Fab")
		)
		(fp_line
			(start 0.12065 -0.2794)
			(end 0.12065 -0.3048)
			(stroke
				(width 0.1)
				(type default)
			)
			(layer "F.Fab")
		)
		(fp_line
			(start 0.12065 -0.3048)
			(end 0.67945 -0.3048)
			(stroke
				(width 0.1)
				(type default)
			)
			(layer "F.Fab")
		)
		(fp_line
			(start 0.120396 0.3048)
			(end 0.120396 0.2794)
			(stroke
				(width 0.1)
				(type default)
			)
			(layer "F.Fab")
		)
		(fp_line
			(start 0.120396 0.2794)
			(end -0.12065 0.2794)
			(stroke
				(width 0.1)
				(type default)
			)
			(layer "F.Fab")
		)
		(fp_line
			(start -0.12065 0.3048)
			(end -0.67945 0.3048)
			(stroke
				(width 0.1)
				(type default)
			)
			(layer "F.Fab")
		)
		(fp_line
			(start -0.12065 0.2794)
			(end -0.12065 0.3048)
			(stroke
				(width 0.1)
				(type default)
			)
			(layer "F.Fab")
		)
		(fp_line
			(start -0.12065 -0.2794)
			(end 0.12065 -0.2794)
			(stroke
				(width 0.1)
				(type default)
			)
			(layer "F.Fab")
		)
		(fp_line
			(start -0.12065 -0.305054)
			(end -0.12065 -0.2794)
			(stroke
				(width 0.1)
				(type default)
			)
			(layer "F.Fab")
		)
		(fp_line
			(start -0.67945 0.3048)
			(end -0.67945 -0.305054)
			(stroke
				(width 0.1)
				(type default)
			)
			(layer "F.Fab")
		)
		(fp_line
			(start -0.67945 -0.305054)
			(end -0.12065 -0.305054)
			(stroke
				(width 0.1)
				(type default)
			)
			(layer "F.Fab")
		)
		(pad "1" smd circle
			(at -0.40005 0 180)
			(size 0 0)
			(layers "F.Cu" "F.Mask" "F.Paste")
			(net "HSC_CS_1")
		)
		(pad "2" smd circle
			(at 0.40005 0 180)
			(size 0 0)
			(layers "F.Cu" "F.Mask" "F.Paste")
			(net "AGND_HSC")
		)
	)
)
